(kicad_pcb
	(version 20241229)
	(generator "pcbnew")
	(generator_version "9.0")
	(general
		(thickness 1.62)
		(legacy_teardrops no)
	)
	(paper "A3")
	(title_block
		(title "COM Express 7 Baseboard")
		(date "2025-02-04")
		(rev "1.1.2")
		(company "Antmicro Ltd")
		(comment 1 "www.antmicro.com")
		(comment 9 "footprints 220-222 of 802")
	)
	(layers
		(0 "F.Cu" signal)
		(4 "In1.Cu" signal)
		(6 "In2.Cu" signal)
		(8 "In3.Cu" signal)
		(10 "In4.Cu" signal)
		(12 "In5.Cu" signal)
		(14 "In6.Cu" signal)
		(2 "B.Cu" signal)
		(9 "F.Adhes" user "F.Adhesive")
		(11 "B.Adhes" user "B.Adhesive")
		(13 "F.Paste" user)
		(15 "B.Paste" user)
		(5 "F.SilkS" user "F.Silkscreen")
		(7 "B.SilkS" user "B.Silkscreen")
		(1 "F.Mask" user)
		(3 "B.Mask" user)
		(17 "Dwgs.User" user "User.Drawings")
		(19 "Cmts.User" user "User.Comments")
		(21 "Eco1.User" user "User.Eco1")
		(23 "Eco2.User" user "User.Eco2")
		(25 "Edge.Cuts" user)
		(27 "Margin" user)
		(31 "F.CrtYd" user "F.Courtyard")
		(29 "B.CrtYd" user "B.Courtyard")
		(35 "F.Fab" user)
		(33 "B.Fab" user)
	)
	(footprint "antmicro-footprints:R_0402_1005Metric"
		(layer "F.Cu")
		(at 283.36 78.06 -90)
		(descr "Resistor SMD 0402")
		(tags "resistor SMD 0402")
		(property "Reference" "R129"
			(at -1.2 0.51 90)
			(layer "F.SilkS")
			(effects
				(font
					(size 0.7 0.7)
					(thickness 0.15)
				)
				(justify right bottom)
			)
		)
		(property "Value" "R_220R_0402"
			(at -1.011843 1.772047 90)
			(layer "F.Fab")
			(effects
				(font
					(size 0.7 0.7)
					(thickness 0.15)
				)
				(justify right bottom)
			)
		)
		(property "Datasheet" "https://www.bourns.com/docs/product-datasheets/cr.pdf"
			(at 0 0 270)
			(layer "F.Fab")
			(hide yes)
			(effects
				(font
					(size 1.27 1.27)
					(thickness 0.15)
				)
			)
		)
		(property "Author" "Antmicro"
			(at 205.3 361.42 0)
			(layer "F.Fab")
			(hide yes)
			(effects
				(font
					(size 1 1)
					(thickness 0.15)
				)
			)
		)
		(property "License" "Apache-2.0"
			(at 205.3 361.42 0)
			(layer "F.Fab")
			(hide yes)
			(effects
				(font
					(size 1 1)
					(thickness 0.15)
				)
			)
		)
		(property "MPN" "CR0402-FX-2200GLF"
			(at 205.3 361.42 0)
			(layer "F.Fab")
			(hide yes)
			(effects
				(font
					(size 1 1)
					(thickness 0.15)
				)
			)
		)
		(property "Manufacturer" "Bourns"
			(at 205.3 361.42 0)
			(layer "F.Fab")
			(hide yes)
			(effects
				(font
					(size 1 1)
					(thickness 0.15)
				)
			)
		)
		(property "Public" "False"
			(at 205.3 361.42 0)
			(layer "F.Fab")
			(hide yes)
			(effects
				(font
					(size 1 1)
					(thickness 0.15)
				)
			)
		)
		(property "Tolerance" "1%"
			(at 205.3 361.42 0)
			(layer "F.Fab")
			(hide yes)
			(effects
				(font
					(size 1 1)
					(thickness 0.15)
				)
			)
		)
		(property "Val" "220R"
			(at 205.3 361.42 0)
			(layer "F.Fab")
			(hide yes)
			(effects
				(font
					(size 1 1)
					(thickness 0.15)
				)
			)
		)
		(sheetname "M.2 key M #2")
		(sheetfile "m2keym.kicad_sch")
		(attr smd)
		(fp_rect
			(start -0.925 -0.47)
			(end 0.925 0.47)
			(stroke
				(width 0.05)
				(type default)
			)
			(fill no)
			(layer "F.CrtYd")
		)
		(fp_rect
			(start -0.5 -0.25)
			(end 0.5 0.25)
			(stroke
				(width 0.15)
				(type solid)
			)
			(fill no)
			(layer "F.Fab")
		)
		(pad "1" smd roundrect
			(at -0.48 0 270)
			(size 0.59 0.64)
			(layers "F.Cu" "F.Mask" "F.Paste")
			(roundrect_rratio 0.25)
			(net 892 "Net-(D14-A)")
			(pintype "passive")
			(teardrops
				(best_length_ratio 0.2)
				(max_length 1)
				(best_width_ratio 0.9)
				(max_width 2)
				(curved_edges yes)
				(filter_ratio 0.9)
				(enabled yes)
				(allow_two_segments yes)
				(prefer_zone_connections yes)
			)
		)
		(pad "2" smd roundrect
			(at 0.48 0 270)
			(size 0.59 0.64)
			(layers "F.Cu" "F.Mask" "F.Paste")
			(roundrect_rratio 0.25)
			(net 2 "+3V3")
			(pintype "passive")
			(teardrops
				(best_length_ratio 0.2)
				(max_length 1)
				(best_width_ratio 0.9)
				(max_width 2)
				(curved_edges yes)
				(filter_ratio 0.9)
				(enabled yes)
				(allow_two_segments yes)
				(prefer_zone_connections yes)
			)
		)
	)
	(footprint "antmicro-footprints:C_Pol_EIA-B"
		(layer "F.Cu")
		(at 110.8 86.96 -90)
		(property "Reference" "C3"
			(at -3.85 -0.55 90)
			(layer "F.SilkS")
			(effects
				(font
					(size 0.7 0.7)
					(thickness 0.15)
				)
				(justify right bottom)
			)
		)
		(property "Value" "C_Pol_100u_10V_KEMET-T520-B"
			(at 0 2.85 90)
			(layer "F.Fab")
			(effects
				(font
					(size 0.7 0.7)
					(thickness 0.15)
				)
				(justify right bottom)
			)
		)
		(property "Datasheet" "https://www.kemet.com/en/us/capacitors/product/T520B107M010ATE070.html"
			(at 0 0 270)
			(layer "F.Fab")
			(hide yes)
			(effects
				(font
					(size 1.27 1.27)
					(thickness 0.15)
				)
			)
		)
		(property "Author" "Antmicro"
			(at 23.84 197.76 0)
			(layer "F.Fab")
			(hide yes)
			(effects
				(font
					(size 1 1)
					(thickness 0.15)
				)
			)
		)
		(property "Dielectric" "template_dielectric"
			(at 23.84 197.76 0)
			(layer "F.Fab")
			(hide yes)
			(effects
				(font
					(size 1 1)
					(thickness 0.15)
				)
			)
		)
		(property "License" "Apache-2.0"
			(at 23.84 197.76 0)
			(layer "F.Fab")
			(hide yes)
			(effects
				(font
					(size 1 1)
					(thickness 0.15)
				)
			)
		)
		(property "MPN" "T520B107M010ATE070"
			(at 23.84 197.76 0)
			(layer "F.Fab")
			(hide yes)
			(effects
				(font
					(size 1 1)
					(thickness 0.15)
				)
			)
		)
		(property "Manufacturer" "KEMET"
			(at 23.84 197.76 0)
			(layer "F.Fab")
			(hide yes)
			(effects
				(font
					(size 1 1)
					(thickness 0.15)
				)
			)
		)
		(property "Public" "False"
			(at 23.84 197.76 0)
			(layer "F.Fab")
			(hide yes)
			(effects
				(font
					(size 1 1)
					(thickness 0.15)
				)
			)
		)
		(property "Val" "100u"
			(at 23.84 197.76 0)
			(layer "F.Fab")
			(hide yes)
			(effects
				(font
					(size 1 1)
					(thickness 0.15)
				)
			)
		)
		(property "Voltage" "10V"
			(at 23.84 197.76 0)
			(layer "F.Fab")
			(hide yes)
			(effects
				(font
					(size 1 1)
					(thickness 0.15)
				)
			)
		)
		(sheetname "2xUSB3.0+RJ45")
		(sheetfile "usb3+rj45.kicad_sch")
		(attr smd)
		(fp_line
			(start 1.8 1.6)
			(end -1.8 1.6)
			(stroke
				(width 0.15)
				(type solid)
			)
			(layer "F.SilkS")
		)
		(fp_line
			(start -1.8 1.3)
			(end -1.8 1.6)
			(stroke
				(width 0.15)
				(type solid)
			)
			(layer "F.SilkS")
		)
		(fp_line
			(start 1.8 1.3)
			(end 1.8 1.6)
			(stroke
				(width 0.15)
				(type solid)
			)
			(layer "F.SilkS")
		)
		(fp_line
			(start -1.8 -1.3)
			(end -1.8 -1.6)
			(stroke
				(width 0.15)
				(type solid)
			)
			(layer "F.SilkS")
		)
		(fp_line
			(start 1.8 -1.3)
			(end 1.8 -1.6)
			(stroke
				(width 0.15)
				(type solid)
			)
			(layer "F.SilkS")
		)
		(fp_line
			(start -2.325 -1.475)
			(end -2.325 -1.878)
			(stroke
				(width 0.15)
				(type solid)
			)
			(layer "F.SilkS")
		)
		(fp_line
			(start -1.8 -1.6)
			(end 1.8 -1.6)
			(stroke
				(width 0.15)
				(type solid)
			)
			(layer "F.SilkS")
		)
		(fp_line
			(start -2.521 -1.676)
			(end -2.123 -1.676)
			(stroke
				(width 0.15)
				(type solid)
			)
			(layer "F.SilkS")
		)
		(fp_line
			(start 1.96 1.75)
			(end -1.97 1.75)
			(stroke
				(width 0.05)
				(type solid)
			)
			(layer "F.CrtYd")
		)
		(fp_line
			(start -1.97 1.35)
			(end -1.97 1.75)
			(stroke
				(width 0.05)
				(type solid)
			)
			(layer "F.CrtYd")
		)
		(fp_line
			(start -1.97 1.35)
			(end -2.41 1.35)
			(stroke
				(width 0.05)
				(type solid)
			)
			(layer "F.CrtYd")
		)
		(fp_line
			(start 1.96 1.35)
			(end 1.96 1.75)
			(stroke
				(width 0.05)
				(type solid)
			)
			(layer "F.CrtYd")
		)
		(fp_line
			(start 2.4 1.35)
			(end 1.96 1.35)
			(stroke
				(width 0.05)
				(type solid)
			)
			(layer "F.CrtYd")
		)
		(fp_line
			(start -2.411 -1.35)
			(end -2.41 1.35)
			(stroke
				(width 0.05)
				(type solid)
			)
			(layer "F.CrtYd")
		)
		(fp_line
			(start -1.97 -1.35)
			(end -2.41 -1.35)
			(stroke
				(width 0.05)
				(type solid)
			)
			(layer "F.CrtYd")
		)
		(fp_line
			(start 2.399 -1.35)
			(end 2.4 1.35)
			(stroke
				(width 0.05)
				(type solid)
			)
			(layer "F.CrtYd")
		)
		(fp_line
			(start 2.399 -1.35)
			(end 1.959 -1.35)
			(stroke
				(width 0.05)
				(type solid)
			)
			(layer "F.CrtYd")
		)
		(fp_line
			(start -1.97 -1.75)
			(end -1.97 -1.35)
			(stroke
				(width 0.05)
				(type solid)
			)
			(layer "F.CrtYd")
		)
		(fp_line
			(start 1.959 -1.75)
			(end 1.959 -1.35)
			(stroke
				(width 0.05)
				(type solid)
			)
			(layer "F.CrtYd")
		)
		(fp_line
			(start 1.959 -1.75)
			(end -1.97 -1.75)
			(stroke
				(width 0.05)
				(type solid)
			)
			(layer "F.CrtYd")
		)
		(fp_line
			(start -1.7 1.324)
			(end -1.551 1.475)
			(stroke
				(width 0.15)
				(type solid)
			)
			(layer "F.Fab")
		)
		(fp_rect
			(start -1.72 -1.5)
			(end 1.719 1.499)
			(stroke
				(width 0.15)
				(type solid)
			)
			(fill no)
			(layer "F.Fab")
		)
		(pad "1" smd roundrect
			(at -1.551 0 270)
			(size 1.2 2.2)
			(layers "F.Cu" "F.Mask" "F.Paste")
			(roundrect_rratio 0.1)
			(net 42 "/2xUSB3.0+RJ45/P1_VBUS")
			(pintype "passive")
			(teardrops
				(best_length_ratio 0.2)
				(max_length 1)
				(best_width_ratio 0.9)
				(max_width 2)
				(curved_edges yes)
				(filter_ratio 0.9)
				(enabled yes)
				(allow_two_segments yes)
				(prefer_zone_connections yes)
			)
		)
		(pad "2" smd roundrect
			(at 1.55 0 270)
			(size 1.2 2.2)
			(layers "F.Cu" "F.Mask" "F.Paste")
			(roundrect_rratio 0.1)
			(net 1 "GND")
			(pintype "passive")
			(teardrops
				(best_length_ratio 0.2)
				(max_length 1)
				(best_width_ratio 0.9)
				(max_width 2)
				(curved_edges yes)
				(filter_ratio 0.9)
				(enabled yes)
				(allow_two_segments yes)
				(prefer_zone_connections yes)
			)
		)
	)
	(footprint "antmicro-footprints:C_0402_1005Metric"
		(layer "F.Cu")
		(at 115.9 148.421 -90)
		(descr "Capacitor SMD 0402")
		(tags "capacitor SMD 0402")
		(property "Reference" "C113"
			(at -12.611 -2.1 90)
			(layer "F.SilkS")
			(effects
				(font
					(size 0.7 0.7)
					(thickness 0.15)
				)
				(justify right bottom)
			)
		)
		(property "Value" "C_100n_0402"
			(at -1.022927 2.155213 90)
			(layer "F.Fab")
			(effects
				(font
					(size 0.7 0.7)
					(thickness 0.15)
				)
				(justify right bottom)
			)
		)
		(property "Datasheet" "https://www.murata.com/products/productdetail?partno=GRM155R61H104KE14%23"
			(at 0 0 270)
			(layer "F.Fab")
			(hide yes)
			(effects
				(font
					(size 1.27 1.27)
					(thickness 0.15)
				)
			)
		)
		(property "Author" "Antmicro"
			(at -32.521 264.321 0)
			(layer "F.Fab")
			(hide yes)
			(effects
				(font
					(size 1 1)
					(thickness 0.15)
				)
			)
		)
		(property "Dielectric" "X5R"
			(at -32.521 264.321 0)
			(layer "F.Fab")
			(hide yes)
			(effects
				(font
					(size 1 1)
					(thickness 0.15)
				)
			)
		)
		(property "License" "Apache-2.0"
			(at -32.521 264.321 0)
			(layer "F.Fab")
			(hide yes)
			(effects
				(font
					(size 1 1)
					(thickness 0.15)
				)
			)
		)
		(property "MPN" "GRM155R61H104KE14D"
			(at -32.521 264.321 0)
			(layer "F.Fab")
			(hide yes)
			(effects
				(font
					(size 1 1)
					(thickness 0.15)
				)
			)
		)
		(property "Manufacturer" "Murata"
			(at -32.521 264.321 0)
			(layer "F.Fab")
			(hide yes)
			(effects
				(font
					(size 1 1)
					(thickness 0.15)
				)
			)
		)
		(property "Public" "False"
			(at -32.521 264.321 0)
			(layer "F.Fab")
			(hide yes)
			(effects
				(font
					(size 1 1)
					(thickness 0.15)
				)
			)
		)
		(property "Val" "100n"
			(at -32.521 264.321 0)
			(layer "F.Fab")
			(hide yes)
			(effects
				(font
					(size 1 1)
					(thickness 0.15)
				)
			)
		)
		(property "Voltage" "50V"
			(at -32.521 264.321 0)
			(layer "F.Fab")
			(hide yes)
			(effects
				(font
					(size 1 1)
					(thickness 0.15)
				)
			)
		)
		(sheetname "PCIe redriver")
		(sheetfile "pcie_redriver.kicad_sch")
		(attr smd)
		(fp_rect
			(start -0.925 -0.47)
			(end 0.925 0.47)
			(stroke
				(width 0.05)
				(type default)
			)
			(fill no)
			(layer "F.CrtYd")
		)
		(fp_line
			(start -0.494 0.248)
			(end -0.494 -0.25)
			(stroke
				(width 0.15)
				(type solid)
			)
			(layer "F.Fab")
		)
		(fp_line
			(start 0.504 0.248)
			(end -0.494 0.248)
			(stroke
				(width 0.15)
				(type solid)
			)
			(layer "F.Fab")
		)
		(fp_line
			(start -0.494 -0.25)
			(end 0.504 -0.25)
			(stroke
				(width 0.15)
				(type solid)
			)
			(layer "F.Fab")
		)
		(fp_line
			(start 0.504 -0.25)
			(end 0.504 0.248)
			(stroke
				(width 0.15)
				(type solid)
			)
			(layer "F.Fab")
		)
		(pad "1" smd roundrect
			(at -0.48 0 270)
			(size 0.59 0.64)
			(layers "F.Cu" "F.Mask" "F.Paste")
			(roundrect_rratio 0.25)
			(net 1 "GND")
			(pintype "passive")
			(teardrops
				(best_length_ratio 0.2)
				(max_length 1)
				(best_width_ratio 0.9)
				(max_width 2)
				(curved_edges yes)
				(filter_ratio 0.9)
				(enabled yes)
				(allow_two_segments yes)
				(prefer_zone_connections yes)
			)
		)
		(pad "2" smd roundrect
			(at 0.48 0 270)
			(size 0.59 0.64)
			(layers "F.Cu" "F.Mask" "F.Paste")
			(roundrect_rratio 0.25)
			(net 2 "+3V3")
			(pintype "passive")
			(teardrops
				(best_length_ratio 0.2)
				(max_length 1)
				(best_width_ratio 0.9)
				(max_width 2)
				(curved_edges yes)
				(filter_ratio 0.9)
				(enabled yes)
				(allow_two_segments yes)
				(prefer_zone_connections yes)
			)
		)
	)
)
